# T6G (Grand Teton) — schematic netlist excerpt (pin names and nets, part order shuffled) for the footprints in the layout excerpt that follows; sources: Cadence DE-HDL packaged netlist, KiCad conversion of 04192023_DAF0TMB3IC0_F0TG_MB_C_brd_V02_OCP.brd

C560  Q_CAP  100UF 4V 20% X6S  pkg C0805  page 279 : A = P0V9_CPU0_RT0_2A ; B = GND
R5029  Q_RES  4.7K 5% EMPTY  pkg 0402LF  page 28 : A = GND ; B = IRQ_TPM_SPI_R_N
PR425  Q_RES  0 5% CHIP  pkg 0402LF  page 213 : A = PVDDCR_CPU0_P1_VOS6 ; B = PVDDCR_CPU0_P1

(kicad_pcb
	(version 20260206)
	(generator "pcbnew")
	(generator_version "10.0")
	(general
		(thickness 1.6)
		(legacy_teardrops no)
	)
	(paper "A4")
	(title_block
		(title "04192023_DAF0TMB3IC0_F0TG_MB_C_brd_V02_OCP.brd")
		(comment 1 "Grand Teton / footprints 5409-5411 of 8354")
	)
	(layers
		(0 "F.Cu" signal "TOP")
		(4 "In1.Cu" signal "GND")
		(6 "In2.Cu" signal "IN1")
		(8 "In3.Cu" signal "GND1")
		(10 "In4.Cu" signal "IN2")
		(12 "In5.Cu" signal "GND2")
		(14 "In6.Cu" signal "IN3")
		(16 "In7.Cu" signal "GND3")
		(18 "In8.Cu" signal "VCC")
		(20 "In9.Cu" signal "VCC1")
		(22 "In10.Cu" signal "GND4")
		(24 "In11.Cu" signal "IN4")
		(26 "In12.Cu" signal "GND5")
		(28 "In13.Cu" signal "IN5")
		(30 "In14.Cu" signal "GND6")
		(32 "In15.Cu" signal "IN6")
		(34 "In16.Cu" signal "GND7")
		(2 "B.Cu" signal "BOTTOM")
		(9 "F.Adhes" user "F.Adhesive")
		(11 "B.Adhes" user "B.Adhesive")
		(13 "F.Paste" user "Package Geometry/Pastemask Top")
		(15 "B.Paste" user "Package Geometry/Pastemask Bottom")
		(5 "F.SilkS" user "Ref Des/Silkscreen Top")
		(7 "B.SilkS" user "Ref Des/Silkscreen Bottom")
		(1 "F.Mask" user "Board Geometry/Soldermask Top")
		(3 "B.Mask" user "Board Geometry/Soldermask Bottom")
		(17 "Dwgs.User" user "User.Drawings")
		(19 "Cmts.User" user "User.Comments")
		(21 "Eco1.User" user "User.Eco1")
		(23 "Eco2.User" user "User.Eco2")
		(25 "Edge.Cuts" user "Board Geometry/Outline")
		(27 "Margin" user)
		(31 "F.CrtYd" user "Package Geometry/Place Bound Top")
		(29 "B.CrtYd" user "Package Geometry/Place Bound Bottom")
		(35 "F.Fab" user "Ref Des/Assembly Top")
		(33 "B.Fab" user "Ref Des/Assembly Bottom")
	)
	(footprint ""
		(layer "B.Cu")
		(at 69.30898 -166.26332 90)
		(property "Reference" "PR425"
			(at 0 0 90)
			(layer "B.SilkS")
			(hide yes)
			(effects
				(font
					(size 1.27 1.27)
				)
				(justify mirror)
			)
		)
		(property "Value" ""
			(at 0 0 90)
			(layer "B.Fab")
			(effects
				(font
					(size 1.27 1.27)
				)
				(justify mirror)
			)
		)
		(duplicate_pad_numbers_are_jumpers no)
		(fp_line
			(start 0.7874 -0.4064)
			(end -0.7874 -0.4064)
			(stroke
				(width 0.1524)
				(type default)
			)
			(layer "B.SilkS")
		)
		(fp_line
			(start -0.7874 -0.4064)
			(end -0.7874 0.4064)
			(stroke
				(width 0.1524)
				(type default)
			)
			(layer "B.SilkS")
		)
		(fp_line
			(start 0.7874 0.4064)
			(end 0.7874 -0.4064)
			(stroke
				(width 0.1524)
				(type default)
			)
			(layer "B.SilkS")
		)
		(fp_line
			(start -0.7874 0.4064)
			(end 0.7874 0.4064)
			(stroke
				(width 0.1524)
				(type default)
			)
			(layer "B.SilkS")
		)
		(fp_line
			(start 0.67945 -0.305054)
			(end 0.12065 -0.305054)
			(stroke
				(width 0.1)
				(type default)
			)
			(layer "B.Fab")
		)
		(fp_line
			(start 0.12065 -0.305054)
			(end 0.12065 -0.2794)
			(stroke
				(width 0.1)
				(type default)
			)
			(layer "B.Fab")
		)
		(fp_line
			(start -0.12065 -0.3048)
			(end -0.67945 -0.3048)
			(stroke
				(width 0.1)
				(type default)
			)
			(layer "B.Fab")
		)
		(fp_line
			(start -0.67945 -0.3048)
			(end -0.67945 0.3048)
			(stroke
				(width 0.1)
				(type default)
			)
			(layer "B.Fab")
		)
		(fp_line
			(start 0.12065 -0.2794)
			(end -0.12065 -0.2794)
			(stroke
				(width 0.1)
				(type default)
			)
			(layer "B.Fab")
		)
		(fp_line
			(start -0.12065 -0.2794)
			(end -0.12065 -0.3048)
			(stroke
				(width 0.1)
				(type default)
			)
			(layer "B.Fab")
		)
		(fp_line
			(start 0.12065 0.2794)
			(end 0.12065 0.3048)
			(stroke
				(width 0.1)
				(type default)
			)
			(layer "B.Fab")
		)
		(fp_line
			(start -0.120396 0.2794)
			(end 0.12065 0.2794)
			(stroke
				(width 0.1)
				(type default)
			)
			(layer "B.Fab")
		)
		(fp_line
			(start 0.67945 0.3048)
			(end 0.67945 -0.305054)
			(stroke
				(width 0.1)
				(type default)
			)
			(layer "B.Fab")
		)
		(fp_line
			(start 0.12065 0.3048)
			(end 0.67945 0.3048)
			(stroke
				(width 0.1)
				(type default)
			)
			(layer "B.Fab")
		)
		(fp_line
			(start -0.120396 0.3048)
			(end -0.120396 0.2794)
			(stroke
				(width 0.1)
				(type default)
			)
			(layer "B.Fab")
		)
		(fp_line
			(start -0.67945 0.3048)
			(end -0.120396 0.3048)
			(stroke
				(width 0.1)
				(type default)
			)
			(layer "B.Fab")
		)
		(pad "1" smd circle
			(at 0.40005 0 270)
			(size 0 0)
			(layers "B.Cu" "B.Mask" "B.Paste")
			(net "PVDDCR_CPU0_P1_VOS6")
		)
		(pad "2" smd circle
			(at -0.40005 0 270)
			(size 0 0)
			(layers "B.Cu" "B.Mask" "B.Paste")
			(net "PVDDCR_CPU0_P1")
		)
	)
	(footprint ""
		(layer "B.Cu")
		(at 325.861426 -398.455134 180)
		(property "Reference" "C560"
			(at 0 0 0)
			(layer "B.SilkS")
			(hide yes)
			(effects
				(font
					(size 1.27 1.27)
				)
				(justify mirror)
			)
		)
		(property "Value" ""
			(at 0 0 0)
			(layer "B.Fab")
			(effects
				(font
					(size 1.27 1.27)
				)
				(justify mirror)
			)
		)
		(duplicate_pad_numbers_are_jumpers no)
		(fp_line
			(start 1.524 0.762)
			(end 1.524 -0.762)
			(stroke
				(width 0.1524)
				(type default)
			)
			(layer "B.SilkS")
		)
		(fp_line
			(start 1.524 -0.762)
			(end -1.524 -0.762)
			(stroke
				(width 0.1524)
				(type default)
			)
			(layer "B.SilkS")
		)
		(fp_line
			(start -1.524 0.762)
			(end 1.524 0.762)
			(stroke
				(width 0.1524)
				(type default)
			)
			(layer "B.SilkS")
		)
		(fp_line
			(start -1.524 -0.762)
			(end -1.524 0.762)
			(stroke
				(width 0.1524)
				(type default)
			)
			(layer "B.SilkS")
		)
		(fp_line
			(start 1.1049 0.724916)
			(end -1.1049 0.724916)
			(stroke
				(width 0.1)
				(type default)
			)
			(layer "B.Fab")
		)
		(fp_line
			(start 1.1049 -0.724916)
			(end 1.1049 0.724916)
			(stroke
				(width 0.1)
				(type default)
			)
			(layer "B.Fab")
		)
		(fp_line
			(start -1.1049 0.724916)
			(end -1.1049 -0.724916)
			(stroke
				(width 0.1)
				(type default)
			)
			(layer "B.Fab")
		)
		(fp_line
			(start -1.1049 -0.724916)
			(end 1.1049 -0.724916)
			(stroke
				(width 0.1)
				(type default)
			)
			(layer "B.Fab")
		)
		(pad "1" smd rect
			(at 0.889 0 180)
			(size 1.016 1.27)
			(layers "B.Cu" "B.Mask" "B.Paste")
			(net "P0V9_CPU0_RT0_2A")
		)
		(pad "2" smd rect
			(at -0.889 0 180)
			(size 1.016 1.27)
			(layers "B.Cu" "B.Mask" "B.Paste")
			(net "GND")
		)
	)
	(footprint ""
		(layer "B.Cu")
		(at 402.322538 -319.198752)
		(property "Reference" "R5029"
			(at 0 0 0)
			(layer "B.SilkS")
			(hide yes)
			(effects
				(font
					(size 1.27 1.27)
				)
				(justify mirror)
			)
		)
		(property "Value" ""
			(at 0 0 0)
			(layer "B.Fab")
			(effects
				(font
					(size 1.27 1.27)
				)
				(justify mirror)
			)
		)
		(duplicate_pad_numbers_are_jumpers no)
		(fp_line
			(start -0.7874 -0.4064)
			(end -0.7874 0.4064)
			(stroke
				(width 0.1524)
				(type default)
			)
			(layer "B.SilkS")
		)
		(fp_line
			(start -0.7874 0.4064)
			(end 0.7874 0.4064)
			(stroke
				(width 0.1524)
				(type default)
			)
			(layer "B.SilkS")
		)
		(fp_line
			(start 0.7874 -0.4064)
			(end -0.7874 -0.4064)
			(stroke
				(width 0.1524)
				(type default)
			)
			(layer "B.SilkS")
		)
		(fp_line
			(start 0.7874 0.4064)
			(end 0.7874 -0.4064)
			(stroke
				(width 0.1524)
				(type default)
			)
			(layer "B.SilkS")
		)
		(fp_line
			(start -0.67945 -0.3048)
			(end -0.67945 0.3048)
			(stroke
				(width 0.1)
				(type default)
			)
			(layer "B.Fab")
		)
		(fp_line
			(start -0.67945 0.3048)
			(end -0.120396 0.3048)
			(stroke
				(width 0.1)
				(type default)
			)
			(layer "B.Fab")
		)
		(fp_line
			(start -0.12065 -0.3048)
			(end -0.67945 -0.3048)
			(stroke
				(width 0.1)
				(type default)
			)
			(layer "B.Fab")
		)
		(fp_line
			(start -0.12065 -0.2794)
			(end -0.12065 -0.3048)
			(stroke
				(width 0.1)
				(type default)
			)
			(layer "B.Fab")
		)
		(fp_line
			(start -0.120396 0.2794)
			(end 0.12065 0.2794)
			(stroke
				(width 0.1)
				(type default)
			)
			(layer "B.Fab")
		)
		(fp_line
			(start -0.120396 0.3048)
			(end -0.120396 0.2794)
			(stroke
				(width 0.1)
				(type default)
			)
			(layer "B.Fab")
		)
		(fp_line
			(start 0.12065 -0.305054)
			(end 0.12065 -0.2794)
			(stroke
				(width 0.1)
				(type default)
			)
			(layer "B.Fab")
		)
		(fp_line
			(start 0.12065 -0.2794)
			(end -0.12065 -0.2794)
			(stroke
				(width 0.1)
				(type default)
			)
			(layer "B.Fab")
		)
		(fp_line
			(start 0.12065 0.2794)
			(end 0.12065 0.3048)
			(stroke
				(width 0.1)
				(type default)
			)
			(layer "B.Fab")
		)
		(fp_line
			(start 0.12065 0.3048)
			(end 0.67945 0.3048)
			(stroke
				(width 0.1)
				(type default)
			)
			(layer "B.Fab")
		)
		(fp_line
			(start 0.67945 -0.305054)
			(end 0.12065 -0.305054)
			(stroke
				(width 0.1)
				(type default)
			)
			(layer "B.Fab")
		)
		(fp_line
			(start 0.67945 0.3048)
			(end 0.67945 -0.305054)
			(stroke
				(width 0.1)
				(type default)
			)
			(layer "B.Fab")
		)
		(pad "1" smd circle
			(at 0.40005 0 180)
			(size 0 0)
			(layers "B.Cu" "B.Mask" "B.Paste")
			(net "GND")
		)
		(pad "2" smd circle
			(at -0.40005 0 180)
			(size 0 0)
			(layers "B.Cu" "B.Mask" "B.Paste")
			(net "IRQ_TPM_SPI_R_N")
		)
	)
)
